# S9S_MB_2U (Grand Teton) — schematic netlist excerpt (pin names and nets, part order shuffled) for the footprints in the layout excerpt that follows; sources: Cadence DE-HDL packaged netlist, KiCad conversion of 03242023_DA0F0TMBIJ0_F0T_Motherboard_J_brd_V01_OCP.brd

PC1207_P1_4  Q_CAP  22UF 4V 20% X6S  pkg C0805  page 290 : A = PVCCFA_EHV_FIVRA_CPU1 ; B = GND
C337  Q_CAP  47UF 4V 20% X6S  pkg C0805  page 78 : A = PVCCIN_CPU1 ; B = GND
C1353  Q_CAP  22UF 4V 20% X6S  pkg C0402  page 79 : A = PVNN_MAIN_CPU1 ; B = GND

(kicad_pcb
	(version 20260206)
	(generator "pcbnew")
	(generator_version "10.0")
	(general
		(thickness 1.6)
		(legacy_teardrops no)
	)
	(paper "A4")
	(title_block
		(title "03242023_DA0F0TMBIJ0_F0T_Motherboard_J_brd_V01_OCP.brd")
		(comment 1 "Grand Teton / footprints 5446-5448 of 6105")
	)
	(layers
		(0 "F.Cu" signal "TOP")
		(4 "In1.Cu" signal "GND")
		(6 "In2.Cu" signal "IN1")
		(8 "In3.Cu" signal "GND1")
		(10 "In4.Cu" signal "IN2")
		(12 "In5.Cu" signal "GND2")
		(14 "In6.Cu" signal "IN3")
		(16 "In7.Cu" signal "GND3")
		(18 "In8.Cu" signal "VCC")
		(20 "In9.Cu" signal "VCC1")
		(22 "In10.Cu" signal "GND4")
		(24 "In11.Cu" signal "IN4")
		(26 "In12.Cu" signal "GND5")
		(28 "In13.Cu" signal "IN5")
		(30 "In14.Cu" signal "GND6")
		(32 "In15.Cu" signal "IN6")
		(34 "In16.Cu" signal "GND7")
		(2 "B.Cu" signal "BOTTOM")
		(9 "F.Adhes" user "F.Adhesive")
		(11 "B.Adhes" user "B.Adhesive")
		(13 "F.Paste" user "Package Geometry/Pastemask Top")
		(15 "B.Paste" user "Package Geometry/Pastemask Bottom")
		(5 "F.SilkS" user "Ref Des/Silkscreen Top")
		(7 "B.SilkS" user "Ref Des/Silkscreen Bottom")
		(1 "F.Mask" user "Board Geometry/Soldermask Top")
		(3 "B.Mask" user "Board Geometry/Soldermask Bottom")
		(17 "Dwgs.User" user "User.Drawings")
		(19 "Cmts.User" user "User.Comments")
		(21 "Eco1.User" user "User.Eco1")
		(23 "Eco2.User" user "User.Eco2")
		(25 "Edge.Cuts" user "Board Geometry/Outline")
		(27 "Margin" user)
		(31 "F.CrtYd" user "Package Geometry/Place Bound Top")
		(29 "B.CrtYd" user "Package Geometry/Place Bound Bottom")
		(35 "F.Fab" user "Ref Des/Assembly Top")
		(33 "B.Fab" user "Ref Des/Assembly Bottom")
	)
	(footprint ""
		(layer "B.Cu")
		(at 106.437938 -236.008164)
		(property "Reference" "C1353"
			(at 0 0 0)
			(layer "B.SilkS")
			(hide yes)
			(effects
				(font
					(size 1.27 1.27)
				)
				(justify mirror)
			)
		)
		(property "Value" ""
			(at 0 0 0)
			(layer "B.Fab")
			(effects
				(font
					(size 1.27 1.27)
				)
				(justify mirror)
			)
		)
		(duplicate_pad_numbers_are_jumpers no)
		(fp_line
			(start -0.7874 -0.4064)
			(end -0.7874 0.4064)
			(stroke
				(width 0.1524)
				(type default)
			)
			(layer "B.SilkS")
		)
		(fp_line
			(start -0.7874 0.4064)
			(end 0.7874 0.4064)
			(stroke
				(width 0.1524)
				(type default)
			)
			(layer "B.SilkS")
		)
		(fp_line
			(start 0.7874 -0.4064)
			(end -0.7874 -0.4064)
			(stroke
				(width 0.1524)
				(type default)
			)
			(layer "B.SilkS")
		)
		(fp_line
			(start 0.7874 0.4064)
			(end 0.7874 -0.4064)
			(stroke
				(width 0.1524)
				(type default)
			)
			(layer "B.SilkS")
		)
		(fp_line
			(start -0.67945 -0.3048)
			(end -0.67945 0.3048)
			(stroke
				(width 0.1)
				(type default)
			)
			(layer "B.Fab")
		)
		(fp_line
			(start -0.67945 0.3048)
			(end -0.120396 0.3048)
			(stroke
				(width 0.1)
				(type default)
			)
			(layer "B.Fab")
		)
		(fp_line
			(start -0.12065 -0.3048)
			(end -0.67945 -0.3048)
			(stroke
				(width 0.1)
				(type default)
			)
			(layer "B.Fab")
		)
		(fp_line
			(start -0.12065 -0.2794)
			(end -0.12065 -0.3048)
			(stroke
				(width 0.1)
				(type default)
			)
			(layer "B.Fab")
		)
		(fp_line
			(start -0.120396 0.2794)
			(end 0.12065 0.2794)
			(stroke
				(width 0.1)
				(type default)
			)
			(layer "B.Fab")
		)
		(fp_line
			(start -0.120396 0.3048)
			(end -0.120396 0.2794)
			(stroke
				(width 0.1)
				(type default)
			)
			(layer "B.Fab")
		)
		(fp_line
			(start 0.12065 -0.305054)
			(end 0.12065 -0.2794)
			(stroke
				(width 0.1)
				(type default)
			)
			(layer "B.Fab")
		)
		(fp_line
			(start 0.12065 -0.2794)
			(end -0.12065 -0.2794)
			(stroke
				(width 0.1)
				(type default)
			)
			(layer "B.Fab")
		)
		(fp_line
			(start 0.12065 0.2794)
			(end 0.12065 0.3048)
			(stroke
				(width 0.1)
				(type default)
			)
			(layer "B.Fab")
		)
		(fp_line
			(start 0.12065 0.3048)
			(end 0.67945 0.3048)
			(stroke
				(width 0.1)
				(type default)
			)
			(layer "B.Fab")
		)
		(fp_line
			(start 0.67945 -0.305054)
			(end 0.12065 -0.305054)
			(stroke
				(width 0.1)
				(type default)
			)
			(layer "B.Fab")
		)
		(fp_line
			(start 0.67945 0.3048)
			(end 0.67945 -0.305054)
			(stroke
				(width 0.1)
				(type default)
			)
			(layer "B.Fab")
		)
		(pad "1" smd circle
			(at 0.40005 0 180)
			(size 0 0)
			(layers "B.Cu" "B.Mask" "B.Paste")
			(net "PVNN_MAIN_CPU1")
		)
		(pad "2" smd circle
			(at -0.40005 0 180)
			(size 0 0)
			(layers "B.Cu" "B.Mask" "B.Paste")
			(net "GND")
		)
	)
	(footprint ""
		(layer "B.Cu")
		(at 118.137178 -241.14379 -90)
		(property "Reference" "C337"
			(at 0 0 90)
			(layer "B.SilkS")
			(hide yes)
			(effects
				(font
					(size 1.27 1.27)
				)
				(justify mirror)
			)
		)
		(property "Value" ""
			(at 0 0 90)
			(layer "B.Fab")
			(effects
				(font
					(size 1.27 1.27)
				)
				(justify mirror)
			)
		)
		(duplicate_pad_numbers_are_jumpers no)
		(fp_line
			(start -1.524 0.762)
			(end 1.524 0.762)
			(stroke
				(width 0.1524)
				(type default)
			)
			(layer "B.SilkS")
		)
		(fp_line
			(start 1.524 0.762)
			(end 1.524 -0.762)
			(stroke
				(width 0.1524)
				(type default)
			)
			(layer "B.SilkS")
		)
		(fp_line
			(start -1.524 -0.762)
			(end -1.524 0.762)
			(stroke
				(width 0.1524)
				(type default)
			)
			(layer "B.SilkS")
		)
		(fp_line
			(start 1.524 -0.762)
			(end -1.524 -0.762)
			(stroke
				(width 0.1524)
				(type default)
			)
			(layer "B.SilkS")
		)
		(fp_line
			(start -1.1049 0.724916)
			(end -1.1049 -0.724916)
			(stroke
				(width 0.1)
				(type default)
			)
			(layer "B.Fab")
		)
		(fp_line
			(start 1.1049 0.724916)
			(end -1.1049 0.724916)
			(stroke
				(width 0.1)
				(type default)
			)
			(layer "B.Fab")
		)
		(fp_line
			(start -1.1049 -0.724916)
			(end 1.1049 -0.724916)
			(stroke
				(width 0.1)
				(type default)
			)
			(layer "B.Fab")
		)
		(fp_line
			(start 1.1049 -0.724916)
			(end 1.1049 0.724916)
			(stroke
				(width 0.1)
				(type default)
			)
			(layer "B.Fab")
		)
		(pad "1" smd rect
			(at 0.889 0 270)
			(size 1.016 1.27)
			(layers "B.Cu" "B.Mask" "B.Paste")
			(net "PVCCIN_CPU1")
		)
		(pad "2" smd rect
			(at -0.889 0 270)
			(size 1.016 1.27)
			(layers "B.Cu" "B.Mask" "B.Paste")
			(net "GND")
		)
	)
	(footprint ""
		(layer "B.Cu")
		(at 45.018706 -344.935556 -90)
		(property "Reference" "PC1207_P1_4"
			(at 0 0 90)
			(layer "B.SilkS")
			(hide yes)
			(effects
				(font
					(size 1.27 1.27)
				)
				(justify mirror)
			)
		)
		(property "Value" ""
			(at 0 0 90)
			(layer "B.Fab")
			(effects
				(font
					(size 1.27 1.27)
				)
				(justify mirror)
			)
		)
		(duplicate_pad_numbers_are_jumpers no)
		(fp_line
			(start -1.524 0.762)
			(end 1.524 0.762)
			(stroke
				(width 0.1524)
				(type default)
			)
			(layer "B.SilkS")
		)
		(fp_line
			(start 1.524 0.762)
			(end 1.524 -0.762)
			(stroke
				(width 0.1524)
				(type default)
			)
			(layer "B.SilkS")
		)
		(fp_line
			(start -1.524 -0.762)
			(end -1.524 0.762)
			(stroke
				(width 0.1524)
				(type default)
			)
			(layer "B.SilkS")
		)
		(fp_line
			(start 1.524 -0.762)
			(end -1.524 -0.762)
			(stroke
				(width 0.1524)
				(type default)
			)
			(layer "B.SilkS")
		)
		(fp_line
			(start -1.1049 0.724916)
			(end -1.1049 -0.724916)
			(stroke
				(width 0.1)
				(type default)
			)
			(layer "B.Fab")
		)
		(fp_line
			(start 1.1049 0.724916)
			(end -1.1049 0.724916)
			(stroke
				(width 0.1)
				(type default)
			)
			(layer "B.Fab")
		)
		(fp_line
			(start -1.1049 -0.724916)
			(end 1.1049 -0.724916)
			(stroke
				(width 0.1)
				(type default)
			)
			(layer "B.Fab")
		)
		(fp_line
			(start 1.1049 -0.724916)
			(end 1.1049 0.724916)
			(stroke
				(width 0.1)
				(type default)
			)
			(layer "B.Fab")
		)
		(pad "1" smd rect
			(at 0.889 0 270)
			(size 1.016 1.27)
			(layers "B.Cu" "B.Mask" "B.Paste")
			(net "PVCCFA_EHV_FIVRA_CPU1")
		)
		(pad "2" smd rect
			(at -0.889 0 270)
			(size 1.016 1.27)
			(layers "B.Cu" "B.Mask" "B.Paste")
			(net "GND")
		)
	)
)
